# T6G (Grand Teton) — schematic netlist excerpt (pin names and nets, part order shuffled) for the footprints in the layout excerpt that follows; sources: Cadence DE-HDL packaged netlist, KiCad conversion of 04192023_DAF0TMB3IC0_F0TG_MB_C_brd_V02_OCP.brd

R3760  Q_RES  10 1% CHIP  pkg 0402LF  page 236 : A = P3V3_E1S_0 ; B = VSENSE_P3V3_INA230_2_INN
PC2188  Q_CAP  1UF 25V 10% X6S  pkg C0402  page 262 : A = P12V_PSU ; B = GND

(kicad_pcb
	(version 20260206)
	(generator "pcbnew")
	(generator_version "10.0")
	(general
		(thickness 1.6)
		(legacy_teardrops no)
	)
	(paper "A4")
	(title_block
		(title "04192023_DAF0TMB3IC0_F0TG_MB_C_brd_V02_OCP.brd")
		(comment 1 "Grand Teton / footprints 4664-4665 of 8354")
	)
	(layers
		(0 "F.Cu" signal "TOP")
		(4 "In1.Cu" signal "GND")
		(6 "In2.Cu" signal "IN1")
		(8 "In3.Cu" signal "GND1")
		(10 "In4.Cu" signal "IN2")
		(12 "In5.Cu" signal "GND2")
		(14 "In6.Cu" signal "IN3")
		(16 "In7.Cu" signal "GND3")
		(18 "In8.Cu" signal "VCC")
		(20 "In9.Cu" signal "VCC1")
		(22 "In10.Cu" signal "GND4")
		(24 "In11.Cu" signal "IN4")
		(26 "In12.Cu" signal "GND5")
		(28 "In13.Cu" signal "IN5")
		(30 "In14.Cu" signal "GND6")
		(32 "In15.Cu" signal "IN6")
		(34 "In16.Cu" signal "GND7")
		(2 "B.Cu" signal "BOTTOM")
		(9 "F.Adhes" user "F.Adhesive")
		(11 "B.Adhes" user "B.Adhesive")
		(13 "F.Paste" user "Package Geometry/Pastemask Top")
		(15 "B.Paste" user "Package Geometry/Pastemask Bottom")
		(5 "F.SilkS" user "Ref Des/Silkscreen Top")
		(7 "B.SilkS" user "Ref Des/Silkscreen Bottom")
		(1 "F.Mask" user "Board Geometry/Soldermask Top")
		(3 "B.Mask" user "Board Geometry/Soldermask Bottom")
		(17 "Dwgs.User" user "User.Drawings")
		(19 "Cmts.User" user "User.Comments")
		(21 "Eco1.User" user "User.Eco1")
		(23 "Eco2.User" user "User.Eco2")
		(25 "Edge.Cuts" user "Board Geometry/Outline")
		(27 "Margin" user)
		(31 "F.CrtYd" user "Package Geometry/Place Bound Top")
		(29 "B.CrtYd" user "Package Geometry/Place Bound Bottom")
		(35 "F.Fab" user "Ref Des/Assembly Top")
		(33 "B.Fab" user "Ref Des/Assembly Bottom")
	)
	(footprint ""
		(layer "F.Cu")
		(at 220.190822 -56.835802 180)
		(property "Reference" "R3760"
			(at 0 0 180)
			(layer "F.SilkS")
			(hide yes)
			(effects
				(font
					(size 1.27 1.27)
				)
			)
		)
		(property "Value" ""
			(at 0 0 180)
			(layer "F.Fab")
			(effects
				(font
					(size 1.27 1.27)
				)
			)
		)
		(duplicate_pad_numbers_are_jumpers no)
		(fp_line
			(start 0.7874 0.4064)
			(end -0.7874 0.4064)
			(stroke
				(width 0.1524)
				(type default)
			)
			(layer "F.SilkS")
		)
		(fp_line
			(start 0.7874 -0.4064)
			(end 0.7874 0.4064)
			(stroke
				(width 0.1524)
				(type default)
			)
			(layer "F.SilkS")
		)
		(fp_line
			(start -0.7874 0.4064)
			(end -0.7874 -0.4064)
			(stroke
				(width 0.1524)
				(type default)
			)
			(layer "F.SilkS")
		)
		(fp_line
			(start -0.7874 -0.4064)
			(end 0.7874 -0.4064)
			(stroke
				(width 0.1524)
				(type default)
			)
			(layer "F.SilkS")
		)
		(fp_line
			(start 0.67945 0.3048)
			(end 0.120396 0.3048)
			(stroke
				(width 0.1)
				(type default)
			)
			(layer "F.Fab")
		)
		(fp_line
			(start 0.67945 -0.3048)
			(end 0.67945 0.3048)
			(stroke
				(width 0.1)
				(type default)
			)
			(layer "F.Fab")
		)
		(fp_line
			(start 0.12065 -0.2794)
			(end 0.12065 -0.3048)
			(stroke
				(width 0.1)
				(type default)
			)
			(layer "F.Fab")
		)
		(fp_line
			(start 0.12065 -0.3048)
			(end 0.67945 -0.3048)
			(stroke
				(width 0.1)
				(type default)
			)
			(layer "F.Fab")
		)
		(fp_line
			(start 0.120396 0.3048)
			(end 0.120396 0.2794)
			(stroke
				(width 0.1)
				(type default)
			)
			(layer "F.Fab")
		)
		(fp_line
			(start 0.120396 0.2794)
			(end -0.12065 0.2794)
			(stroke
				(width 0.1)
				(type default)
			)
			(layer "F.Fab")
		)
		(fp_line
			(start -0.12065 0.3048)
			(end -0.67945 0.3048)
			(stroke
				(width 0.1)
				(type default)
			)
			(layer "F.Fab")
		)
		(fp_line
			(start -0.12065 0.2794)
			(end -0.12065 0.3048)
			(stroke
				(width 0.1)
				(type default)
			)
			(layer "F.Fab")
		)
		(fp_line
			(start -0.12065 -0.2794)
			(end 0.12065 -0.2794)
			(stroke
				(width 0.1)
				(type default)
			)
			(layer "F.Fab")
		)
		(fp_line
			(start -0.12065 -0.305054)
			(end -0.12065 -0.2794)
			(stroke
				(width 0.1)
				(type default)
			)
			(layer "F.Fab")
		)
		(fp_line
			(start -0.67945 0.3048)
			(end -0.67945 -0.305054)
			(stroke
				(width 0.1)
				(type default)
			)
			(layer "F.Fab")
		)
		(fp_line
			(start -0.67945 -0.305054)
			(end -0.12065 -0.305054)
			(stroke
				(width 0.1)
				(type default)
			)
			(layer "F.Fab")
		)
		(pad "1" smd circle
			(at -0.40005 0 180)
			(size 0 0)
			(layers "F.Cu" "F.Mask" "F.Paste")
			(net "P3V3_E1S_0")
		)
		(pad "2" smd circle
			(at 0.40005 0 180)
			(size 0 0)
			(layers "F.Cu" "F.Mask" "F.Paste")
			(net "VSENSE_P3V3_INA230_2_INN")
		)
	)
	(footprint ""
		(layer "F.Cu")
		(at 184.622694 -409.128722 180)
		(property "Reference" "PC2188"
			(at 0 0 180)
			(layer "F.SilkS")
			(hide yes)
			(effects
				(font
					(size 1.27 1.27)
				)
			)
		)
		(property "Value" ""
			(at 0 0 180)
			(layer "F.Fab")
			(effects
				(font
					(size 1.27 1.27)
				)
			)
		)
		(duplicate_pad_numbers_are_jumpers no)
		(fp_line
			(start 0.7874 0.4064)
			(end -0.7874 0.4064)
			(stroke
				(width 0.1524)
				(type default)
			)
			(layer "F.SilkS")
		)
		(fp_line
			(start 0.7874 -0.4064)
			(end 0.7874 0.4064)
			(stroke
				(width 0.1524)
				(type default)
			)
			(layer "F.SilkS")
		)
		(fp_line
			(start -0.7874 0.4064)
			(end -0.7874 -0.4064)
			(stroke
				(width 0.1524)
				(type default)
			)
			(layer "F.SilkS")
		)
		(fp_line
			(start -0.7874 -0.4064)
			(end 0.7874 -0.4064)
			(stroke
				(width 0.1524)
				(type default)
			)
			(layer "F.SilkS")
		)
		(fp_line
			(start 0.67945 0.3048)
			(end 0.120396 0.3048)
			(stroke
				(width 0.1)
				(type default)
			)
			(layer "F.Fab")
		)
		(fp_line
			(start 0.67945 -0.3048)
			(end 0.67945 0.3048)
			(stroke
				(width 0.1)
				(type default)
			)
			(layer "F.Fab")
		)
		(fp_line
			(start 0.12065 -0.2794)
			(end 0.12065 -0.3048)
			(stroke
				(width 0.1)
				(type default)
			)
			(layer "F.Fab")
		)
		(fp_line
			(start 0.12065 -0.3048)
			(end 0.67945 -0.3048)
			(stroke
				(width 0.1)
				(type default)
			)
			(layer "F.Fab")
		)
		(fp_line
			(start 0.120396 0.3048)
			(end 0.120396 0.2794)
			(stroke
				(width 0.1)
				(type default)
			)
			(layer "F.Fab")
		)
		(fp_line
			(start 0.120396 0.2794)
			(end -0.12065 0.2794)
			(stroke
				(width 0.1)
				(type default)
			)
			(layer "F.Fab")
		)
		(fp_line
			(start -0.12065 0.3048)
			(end -0.67945 0.3048)
			(stroke
				(width 0.1)
				(type default)
			)
			(layer "F.Fab")
		)
		(fp_line
			(start -0.12065 0.2794)
			(end -0.12065 0.3048)
			(stroke
				(width 0.1)
				(type default)
			)
			(layer "F.Fab")
		)
		(fp_line
			(start -0.12065 -0.2794)
			(end 0.12065 -0.2794)
			(stroke
				(width 0.1)
				(type default)
			)
			(layer "F.Fab")
		)
		(fp_line
			(start -0.12065 -0.305054)
			(end -0.12065 -0.2794)
			(stroke
				(width 0.1)
				(type default)
			)
			(layer "F.Fab")
		)
		(fp_line
			(start -0.67945 0.3048)
			(end -0.67945 -0.305054)
			(stroke
				(width 0.1)
				(type default)
			)
			(layer "F.Fab")
		)
		(fp_line
			(start -0.67945 -0.305054)
			(end -0.12065 -0.305054)
			(stroke
				(width 0.1)
				(type default)
			)
			(layer "F.Fab")
		)
		(pad "1" smd circle
			(at -0.40005 0 180)
			(size 0 0)
			(layers "F.Cu" "F.Mask" "F.Paste")
			(net "P12V_PSU")
		)
		(pad "2" smd circle
			(at 0.40005 0 180)
			(size 0 0)
			(layers "F.Cu" "F.Mask" "F.Paste")
			(net "GND")
		)
	)
)
